# T6G (Grand Teton) — schematic netlist excerpt (pin names and nets, part order shuffled) for the footprints in the layout excerpt that follows; sources: Cadence DE-HDL packaged netlist, KiCad conversion of 04192023_DAF0TMB3IC0_F0TG_MB_C_brd_V02_OCP.brd

R311  Q_RES  1K 1% CHIP  pkg 0402LF  page 106 : A = PWRGD_CHI_CPU1_DIMM ; B = PWRGD_CHGL_CPU1
R2  Q_RES  33.2 1% CHIP  pkg 0402LF  page 85 : A = RST_PERST_CPU1_SWB_1_N ; B = RST_PERST_CPU1_SWB_1_R_N
C6726  Q_CAP_DIFFBUS  DIFF BUS_0.22UF 6.3V 20% X6S  pkg C0201  page 352 : \1\ = P5E_CPU1_P3_TX_BUF_C_DN<0> ; \2\ = P5E_CPU1_P3_TX_BUF_DN<0>

(kicad_pcb
	(version 20260206)
	(generator "pcbnew")
	(generator_version "10.0")
	(general
		(thickness 1.6)
		(legacy_teardrops no)
	)
	(paper "A4")
	(title_block
		(title "04192023_DAF0TMB3IC0_F0TG_MB_C_brd_V02_OCP.brd")
		(comment 1 "Grand Teton / footprints 7870-7872 of 8354")
	)
	(layers
		(0 "F.Cu" signal "TOP")
		(4 "In1.Cu" signal "GND")
		(6 "In2.Cu" signal "IN1")
		(8 "In3.Cu" signal "GND1")
		(10 "In4.Cu" signal "IN2")
		(12 "In5.Cu" signal "GND2")
		(14 "In6.Cu" signal "IN3")
		(16 "In7.Cu" signal "GND3")
		(18 "In8.Cu" signal "VCC")
		(20 "In9.Cu" signal "VCC1")
		(22 "In10.Cu" signal "GND4")
		(24 "In11.Cu" signal "IN4")
		(26 "In12.Cu" signal "GND5")
		(28 "In13.Cu" signal "IN5")
		(30 "In14.Cu" signal "GND6")
		(32 "In15.Cu" signal "IN6")
		(34 "In16.Cu" signal "GND7")
		(2 "B.Cu" signal "BOTTOM")
		(9 "F.Adhes" user "F.Adhesive")
		(11 "B.Adhes" user "B.Adhesive")
		(13 "F.Paste" user "Package Geometry/Pastemask Top")
		(15 "B.Paste" user "Package Geometry/Pastemask Bottom")
		(5 "F.SilkS" user "Ref Des/Silkscreen Top")
		(7 "B.SilkS" user "Ref Des/Silkscreen Bottom")
		(1 "F.Mask" user "Board Geometry/Soldermask Top")
		(3 "B.Mask" user "Board Geometry/Soldermask Bottom")
		(17 "Dwgs.User" user "User.Drawings")
		(19 "Cmts.User" user "User.Comments")
		(21 "Eco1.User" user "User.Eco1")
		(23 "Eco2.User" user "User.Eco2")
		(25 "Edge.Cuts" user "Board Geometry/Outline")
		(27 "Margin" user)
		(31 "F.CrtYd" user "Package Geometry/Place Bound Top")
		(29 "B.CrtYd" user "Package Geometry/Place Bound Bottom")
		(35 "F.Fab" user "Ref Des/Assembly Top")
		(33 "B.Fab" user "Ref Des/Assembly Bottom")
	)
	(footprint ""
		(layer "B.Cu")
		(at 179.32146 -190.948564 180)
		(property "Reference" "R311"
			(at 0 0 0)
			(layer "B.SilkS")
			(hide yes)
			(effects
				(font
					(size 1.27 1.27)
				)
				(justify mirror)
			)
		)
		(property "Value" ""
			(at 0 0 0)
			(layer "B.Fab")
			(effects
				(font
					(size 1.27 1.27)
				)
				(justify mirror)
			)
		)
		(duplicate_pad_numbers_are_jumpers no)
		(fp_line
			(start 0.7874 0.4064)
			(end 0.7874 -0.4064)
			(stroke
				(width 0.1524)
				(type default)
			)
			(layer "B.SilkS")
		)
		(fp_line
			(start 0.7874 -0.4064)
			(end -0.7874 -0.4064)
			(stroke
				(width 0.1524)
				(type default)
			)
			(layer "B.SilkS")
		)
		(fp_line
			(start -0.7874 0.4064)
			(end 0.7874 0.4064)
			(stroke
				(width 0.1524)
				(type default)
			)
			(layer "B.SilkS")
		)
		(fp_line
			(start -0.7874 -0.4064)
			(end -0.7874 0.4064)
			(stroke
				(width 0.1524)
				(type default)
			)
			(layer "B.SilkS")
		)
		(fp_line
			(start 0.67945 0.3048)
			(end 0.67945 -0.305054)
			(stroke
				(width 0.1)
				(type default)
			)
			(layer "B.Fab")
		)
		(fp_line
			(start 0.67945 -0.305054)
			(end 0.12065 -0.305054)
			(stroke
				(width 0.1)
				(type default)
			)
			(layer "B.Fab")
		)
		(fp_line
			(start 0.12065 0.3048)
			(end 0.67945 0.3048)
			(stroke
				(width 0.1)
				(type default)
			)
			(layer "B.Fab")
		)
		(fp_line
			(start 0.12065 0.2794)
			(end 0.12065 0.3048)
			(stroke
				(width 0.1)
				(type default)
			)
			(layer "B.Fab")
		)
		(fp_line
			(start 0.12065 -0.2794)
			(end -0.12065 -0.2794)
			(stroke
				(width 0.1)
				(type default)
			)
			(layer "B.Fab")
		)
		(fp_line
			(start 0.12065 -0.305054)
			(end 0.12065 -0.2794)
			(stroke
				(width 0.1)
				(type default)
			)
			(layer "B.Fab")
		)
		(fp_line
			(start -0.120396 0.3048)
			(end -0.120396 0.2794)
			(stroke
				(width 0.1)
				(type default)
			)
			(layer "B.Fab")
		)
		(fp_line
			(start -0.120396 0.2794)
			(end 0.12065 0.2794)
			(stroke
				(width 0.1)
				(type default)
			)
			(layer "B.Fab")
		)
		(fp_line
			(start -0.12065 -0.2794)
			(end -0.12065 -0.3048)
			(stroke
				(width 0.1)
				(type default)
			)
			(layer "B.Fab")
		)
		(fp_line
			(start -0.12065 -0.3048)
			(end -0.67945 -0.3048)
			(stroke
				(width 0.1)
				(type default)
			)
			(layer "B.Fab")
		)
		(fp_line
			(start -0.67945 0.3048)
			(end -0.120396 0.3048)
			(stroke
				(width 0.1)
				(type default)
			)
			(layer "B.Fab")
		)
		(fp_line
			(start -0.67945 -0.3048)
			(end -0.67945 0.3048)
			(stroke
				(width 0.1)
				(type default)
			)
			(layer "B.Fab")
		)
		(pad "1" smd circle
			(at 0.40005 0)
			(size 0 0)
			(layers "B.Cu" "B.Mask" "B.Paste")
			(net "PWRGD_CHI_CPU1_DIMM")
		)
		(pad "2" smd circle
			(at -0.40005 0)
			(size 0 0)
			(layers "B.Cu" "B.Mask" "B.Paste")
			(net "PWRGD_CHGL_CPU1")
		)
	)
	(footprint ""
		(layer "B.Cu")
		(at 201.12355 -115.955572 180)
		(property "Reference" "R2"
			(at 0 0 0)
			(layer "B.SilkS")
			(hide yes)
			(effects
				(font
					(size 1.27 1.27)
				)
				(justify mirror)
			)
		)
		(property "Value" ""
			(at 0 0 0)
			(layer "B.Fab")
			(effects
				(font
					(size 1.27 1.27)
				)
				(justify mirror)
			)
		)
		(duplicate_pad_numbers_are_jumpers no)
		(fp_line
			(start 0.7874 0.4064)
			(end 0.7874 -0.4064)
			(stroke
				(width 0.1524)
				(type default)
			)
			(layer "B.SilkS")
		)
		(fp_line
			(start 0.7874 -0.4064)
			(end -0.7874 -0.4064)
			(stroke
				(width 0.1524)
				(type default)
			)
			(layer "B.SilkS")
		)
		(fp_line
			(start -0.7874 0.4064)
			(end 0.7874 0.4064)
			(stroke
				(width 0.1524)
				(type default)
			)
			(layer "B.SilkS")
		)
		(fp_line
			(start -0.7874 -0.4064)
			(end -0.7874 0.4064)
			(stroke
				(width 0.1524)
				(type default)
			)
			(layer "B.SilkS")
		)
		(fp_line
			(start 0.67945 0.3048)
			(end 0.67945 -0.305054)
			(stroke
				(width 0.1)
				(type default)
			)
			(layer "B.Fab")
		)
		(fp_line
			(start 0.67945 -0.305054)
			(end 0.12065 -0.305054)
			(stroke
				(width 0.1)
				(type default)
			)
			(layer "B.Fab")
		)
		(fp_line
			(start 0.12065 0.3048)
			(end 0.67945 0.3048)
			(stroke
				(width 0.1)
				(type default)
			)
			(layer "B.Fab")
		)
		(fp_line
			(start 0.12065 0.2794)
			(end 0.12065 0.3048)
			(stroke
				(width 0.1)
				(type default)
			)
			(layer "B.Fab")
		)
		(fp_line
			(start 0.12065 -0.2794)
			(end -0.12065 -0.2794)
			(stroke
				(width 0.1)
				(type default)
			)
			(layer "B.Fab")
		)
		(fp_line
			(start 0.12065 -0.305054)
			(end 0.12065 -0.2794)
			(stroke
				(width 0.1)
				(type default)
			)
			(layer "B.Fab")
		)
		(fp_line
			(start -0.120396 0.3048)
			(end -0.120396 0.2794)
			(stroke
				(width 0.1)
				(type default)
			)
			(layer "B.Fab")
		)
		(fp_line
			(start -0.120396 0.2794)
			(end 0.12065 0.2794)
			(stroke
				(width 0.1)
				(type default)
			)
			(layer "B.Fab")
		)
		(fp_line
			(start -0.12065 -0.2794)
			(end -0.12065 -0.3048)
			(stroke
				(width 0.1)
				(type default)
			)
			(layer "B.Fab")
		)
		(fp_line
			(start -0.12065 -0.3048)
			(end -0.67945 -0.3048)
			(stroke
				(width 0.1)
				(type default)
			)
			(layer "B.Fab")
		)
		(fp_line
			(start -0.67945 0.3048)
			(end -0.120396 0.3048)
			(stroke
				(width 0.1)
				(type default)
			)
			(layer "B.Fab")
		)
		(fp_line
			(start -0.67945 -0.3048)
			(end -0.67945 0.3048)
			(stroke
				(width 0.1)
				(type default)
			)
			(layer "B.Fab")
		)
		(pad "1" smd circle
			(at 0.40005 0)
			(size 0 0)
			(layers "B.Cu" "B.Mask" "B.Paste")
			(net "RST_PERST_CPU1_SWB_1_N")
		)
		(pad "2" smd circle
			(at -0.40005 0)
			(size 0 0)
			(layers "B.Cu" "B.Mask" "B.Paste")
			(net "RST_PERST_CPU1_SWB_1_R_N")
		)
	)
	(footprint ""
		(layer "B.Cu")
		(at 116.400326 -408.517344 90)
		(property "Reference" "C6726"
			(at 0 0 90)
			(layer "B.SilkS")
			(hide yes)
			(effects
				(font
					(size 1.27 1.27)
				)
				(justify mirror)
			)
		)
		(property "Value" ""
			(at 0 0 90)
			(layer "B.Fab")
			(effects
				(font
					(size 1.27 1.27)
				)
				(justify mirror)
			)
		)
		(duplicate_pad_numbers_are_jumpers no)
		(fp_line
			(start 0.299974 -0.150114)
			(end -0.299974 -0.150114)
			(stroke
				(width 0.1)
				(type default)
			)
			(layer "B.Fab")
		)
		(fp_line
			(start -0.299974 -0.150114)
			(end -0.299974 0.150114)
			(stroke
				(width 0.1)
				(type default)
			)
			(layer "B.Fab")
		)
		(fp_line
			(start 0.299974 0.150114)
			(end 0.299974 -0.150114)
			(stroke
				(width 0.1)
				(type default)
			)
			(layer "B.Fab")
		)
		(fp_line
			(start -0.299974 0.150114)
			(end 0.299974 0.150114)
			(stroke
				(width 0.1)
				(type default)
			)
			(layer "B.Fab")
		)
		(pad "1" smd rect
			(at 0.2667 0 270)
			(size 0.3048 0.381)
			(layers "B.Cu" "B.Mask" "B.Paste")
			(net "P5E_CPU1_P3_TX_BUF_C_DN<0>")
		)
		(pad "2" smd rect
			(at -0.2667 0 270)
			(size 0.3048 0.381)
			(layers "B.Cu" "B.Mask" "B.Paste")
			(net "P5E_CPU1_P3_TX_BUF_DN<0>")
		)
	)
)
